(kicad_pcb
	(version 20260206)
	(generator "pcbnew")
	(generator_version "10.0")
	(general
		(thickness 1.6)
		(legacy_teardrops no)
	)
	(paper "A4")
	(title_block
		(title "01162023_DA0F0TEBIF0_F0T_Expander_BD_F_brd_V02_OCP.brd")
		(comment 1 "Grand Teton / footprints 1466-1471 of 9728")
	)
	(layers
		(0 "F.Cu" signal "TOP")
		(4 "In1.Cu" signal "GND")
		(6 "In2.Cu" signal "VCC")
		(8 "In3.Cu" signal "VCC1")
		(10 "In4.Cu" signal "GND1")
		(12 "In5.Cu" signal "IN1")
		(14 "In6.Cu" signal "GND2")
		(16 "In7.Cu" signal "IN2")
		(18 "In8.Cu" signal "GND3")
		(20 "In9.Cu" signal "IN3")
		(22 "In10.Cu" signal "GND4")
		(24 "In11.Cu" signal "IN4")
		(26 "In12.Cu" signal "GND5")
		(28 "In13.Cu" signal "IN5")
		(30 "In14.Cu" signal "GND6")
		(32 "In15.Cu" signal "IN6")
		(34 "In16.Cu" signal "GND7")
		(2 "B.Cu" signal "BOTTOM")
		(9 "F.Adhes" user "F.Adhesive")
		(11 "B.Adhes" user "B.Adhesive")
		(13 "F.Paste" user "Package Geometry/Pastemask Top")
		(15 "B.Paste" user "Package Geometry/Pastemask Bottom")
		(5 "F.SilkS" user "Ref Des/Silkscreen Top")
		(7 "B.SilkS" user "Ref Des/Silkscreen Bottom")
		(1 "F.Mask" user "Board Geometry/Soldermask Top")
		(3 "B.Mask" user "Board Geometry/Soldermask Bottom")
		(17 "Dwgs.User" user "User.Drawings")
		(19 "Cmts.User" user "User.Comments")
		(21 "Eco1.User" user "User.Eco1")
		(23 "Eco2.User" user "User.Eco2")
		(25 "Edge.Cuts" user "Board Geometry/Outline")
		(27 "Margin" user)
		(31 "F.CrtYd" user "Package Geometry/Place Bound Top")
		(29 "B.CrtYd" user "Package Geometry/Place Bound Bottom")
		(35 "F.Fab" user "Ref Des/Assembly Top")
		(33 "B.Fab" user "Ref Des/Assembly Bottom")
	)
	(footprint ""
		(layer "F.Cu")
		(at 350.380554 -89.502234)
		(property "Reference" "R1591"
			(at 0 0 0)
			(layer "F.SilkS")
			(hide yes)
			(effects
				(font
					(size 1.27 1.27)
				)
			)
		)
		(property "Value" ""
			(at 0 0 0)
			(layer "F.Fab")
			(effects
				(font
					(size 1.27 1.27)
				)
			)
		)
		(duplicate_pad_numbers_are_jumpers no)
		(fp_line
			(start -0.7874 -0.4064)
			(end 0.7874 -0.4064)
			(stroke
				(width 0.1524)
				(type default)
			)
			(layer "F.SilkS")
		)
		(fp_line
			(start -0.7874 0.4064)
			(end -0.7874 -0.4064)
			(stroke
				(width 0.1524)
				(type default)
			)
			(layer "F.SilkS")
		)
		(fp_line
			(start 0.7874 -0.4064)
			(end 0.7874 0.4064)
			(stroke
				(width 0.1524)
				(type default)
			)
			(layer "F.SilkS")
		)
		(fp_line
			(start 0.7874 0.4064)
			(end -0.7874 0.4064)
			(stroke
				(width 0.1524)
				(type default)
			)
			(layer "F.SilkS")
		)
		(fp_line
			(start -0.67945 -0.305054)
			(end -0.12065 -0.305054)
			(stroke
				(width 0.1)
				(type default)
			)
			(layer "F.Fab")
		)
		(fp_line
			(start -0.67945 0.3048)
			(end -0.67945 -0.305054)
			(stroke
				(width 0.1)
				(type default)
			)
			(layer "F.Fab")
		)
		(fp_line
			(start -0.12065 -0.305054)
			(end -0.12065 -0.2794)
			(stroke
				(width 0.1)
				(type default)
			)
			(layer "F.Fab")
		)
		(fp_line
			(start -0.12065 -0.2794)
			(end 0.12065 -0.2794)
			(stroke
				(width 0.1)
				(type default)
			)
			(layer "F.Fab")
		)
		(fp_line
			(start -0.12065 0.2794)
			(end -0.12065 0.3048)
			(stroke
				(width 0.1)
				(type default)
			)
			(layer "F.Fab")
		)
		(fp_line
			(start -0.12065 0.3048)
			(end -0.67945 0.3048)
			(stroke
				(width 0.1)
				(type default)
			)
			(layer "F.Fab")
		)
		(fp_line
			(start 0.120396 0.2794)
			(end -0.12065 0.2794)
			(stroke
				(width 0.1)
				(type default)
			)
			(layer "F.Fab")
		)
		(fp_line
			(start 0.120396 0.3048)
			(end 0.120396 0.2794)
			(stroke
				(width 0.1)
				(type default)
			)
			(layer "F.Fab")
		)
		(fp_line
			(start 0.12065 -0.3048)
			(end 0.67945 -0.3048)
			(stroke
				(width 0.1)
				(type default)
			)
			(layer "F.Fab")
		)
		(fp_line
			(start 0.12065 -0.2794)
			(end 0.12065 -0.3048)
			(stroke
				(width 0.1)
				(type default)
			)
			(layer "F.Fab")
		)
		(fp_line
			(start 0.67945 -0.3048)
			(end 0.67945 0.3048)
			(stroke
				(width 0.1)
				(type default)
			)
			(layer "F.Fab")
		)
		(fp_line
			(start 0.67945 0.3048)
			(end 0.120396 0.3048)
			(stroke
				(width 0.1)
				(type default)
			)
			(layer "F.Fab")
		)
		(pad "1" smd circle
			(at -0.40005 0)
			(size 0 0)
			(layers "F.Cu" "F.Mask" "F.Paste")
			(net "P3V3_AUX")
		)
		(pad "2" smd circle
			(at 0.40005 0)
			(size 0 0)
			(layers "F.Cu" "F.Mask" "F.Paste")
			(net "SMB_BIC_I2C9_MUX1_SSD8_R_SDA")
		)
	)
	(footprint ""
		(layer "F.Cu")
		(at 323.511926 -100.20935 90)
		(property "Reference" "U84"
			(at 0.42545 2.371344 90)
			(unlocked yes)
			(layer "F.SilkS")
			(effects
				(font
					(size 0.7874 0.5842)
					(thickness 0.1524)
				)
			)
		)
		(property "Value" ""
			(at 0 0 90)
			(layer "F.Fab")
			(effects
				(font
					(size 1.27 1.27)
				)
			)
		)
		(duplicate_pad_numbers_are_jumpers no)
		(fp_line
			(start 1.500124 -1.500124)
			(end 1.500124 -1.004062)
			(stroke
				(width 0.1524)
				(type default)
			)
			(layer "F.SilkS")
		)
		(fp_line
			(start 1.004062 -1.500124)
			(end 1.500124 -1.500124)
			(stroke
				(width 0.1524)
				(type default)
			)
			(layer "F.SilkS")
		)
		(fp_line
			(start -1.500124 -1.500124)
			(end -1.004062 -1.500124)
			(stroke
				(width 0.1524)
				(type default)
			)
			(layer "F.SilkS")
		)
		(fp_line
			(start -1.500124 -1.004062)
			(end -1.500124 -1.500124)
			(stroke
				(width 0.1524)
				(type default)
			)
			(layer "F.SilkS")
		)
		(fp_line
			(start 1.500124 1.004062)
			(end 1.500124 1.500124)
			(stroke
				(width 0.1524)
				(type default)
			)
			(layer "F.SilkS")
		)
		(fp_line
			(start 1.500124 1.500124)
			(end 1.004062 1.500124)
			(stroke
				(width 0.1524)
				(type default)
			)
			(layer "F.SilkS")
		)
		(fp_line
			(start -1.004062 1.500124)
			(end -1.500124 1.500124)
			(stroke
				(width 0.1524)
				(type default)
			)
			(layer "F.SilkS")
		)
		(fp_line
			(start -1.500124 1.500124)
			(end -1.500124 1.004062)
			(stroke
				(width 0.1524)
				(type default)
			)
			(layer "F.SilkS")
		)
		(fp_poly
			(pts
				(xy -1.968246 -2.281936) (xy -2.686812 -1.563624) (xy -1.60909 -1.204468)
			)
			(stroke
				(width 0)
				(type default)
			)
			(fill yes)
			(layer "F.SilkS")
		)
		(fp_line
			(start 1.500124 -1.500124)
			(end 1.500124 1.500124)
			(stroke
				(width 0.1)
				(type default)
			)
			(layer "F.Fab")
		)
		(fp_line
			(start -1.500124 -1.500124)
			(end 1.500124 -1.500124)
			(stroke
				(width 0.1)
				(type default)
			)
			(layer "F.Fab")
		)
		(fp_line
			(start 1.500124 1.500124)
			(end -1.500124 1.500124)
			(stroke
				(width 0.1)
				(type default)
			)
			(layer "F.Fab")
		)
		(fp_line
			(start -1.500124 1.500124)
			(end -1.500124 -1.500124)
			(stroke
				(width 0.1)
				(type default)
			)
			(layer "F.Fab")
		)
		(fp_poly
			(pts
				(xy -2.847848 -1.258062) (xy -2.847848 -0.242062) (xy -1.831848 -0.750062)
			)
			(stroke
				(width 0)
				(type default)
			)
			(fill yes)
			(layer "F.Fab")
		)
		(pad "1" smd rect
			(at -1.400048 -0.750062)
			(size 0.2286 0.6096)
			(layers "F.Cu" "F.Mask" "F.Paste")
			(net "NIC5_ADC_A1")
		)
		(pad "2" smd rect
			(at -1.400048 -0.249936)
			(size 0.2286 0.6096)
			(layers "F.Cu" "F.Mask" "F.Paste")
			(net "NIC5_ADC_A0")
		)
		(pad "3" smd rect
			(at -1.400048 0.249936)
			(size 0.2286 0.6096)
			(layers "F.Cu" "F.Mask" "F.Paste")
			(net "NIC5_ADC_ALERT_N")
		)
		(pad "4" smd rect
			(at -1.400048 0.750062)
			(size 0.2286 0.6096)
			(layers "F.Cu" "F.Mask" "F.Paste")
			(net "SMB_NIC5_ADC_SDA")
		)
		(pad "5" smd rect
			(at -0.750062 1.400048 90)
			(size 0.2286 0.6096)
			(layers "F.Cu" "F.Mask" "F.Paste")
			(net "SMB_NIC5_ADC_SCL")
		)
		(pad "6" smd rect
			(at -0.249936 1.400048 90)
			(size 0.2286 0.6096)
			(layers "F.Cu" "F.Mask" "F.Paste")
			(net "Net_8636")
		)
		(pad "7" smd rect
			(at 0.249936 1.400048 90)
			(size 0.2286 0.6096)
			(layers "F.Cu" "F.Mask" "F.Paste")
			(net "Net_8635")
		)
		(pad "8" smd rect
			(at 0.750062 1.400048 90)
			(size 0.2286 0.6096)
			(layers "F.Cu" "F.Mask" "F.Paste")
			(net "Net_8634")
		)
		(pad "9" smd rect
			(at 1.400048 0.750062)
			(size 0.2286 0.6096)
			(layers "F.Cu" "F.Mask" "F.Paste")
			(net "P3V3_AUX")
		)
		(pad "10" smd rect
			(at 1.400048 0.249936)
			(size 0.2286 0.6096)
			(layers "F.Cu" "F.Mask" "F.Paste")
			(net "GND")
		)
		(pad "11" smd rect
			(at 1.400048 -0.249936)
			(size 0.2286 0.6096)
			(layers "F.Cu" "F.Mask" "F.Paste")
			(net "P12V_NIC5_R")
		)
		(pad "12" smd rect
			(at 1.400048 -0.750062)
			(size 0.2286 0.6096)
			(layers "F.Cu" "F.Mask" "F.Paste")
			(net "P12V_NIC5_VIN_N")
		)
		(pad "13" smd rect
			(at 0.750062 -1.400048 90)
			(size 0.2286 0.6096)
			(layers "F.Cu" "F.Mask" "F.Paste")
			(net "P12V_NIC5_VIN_P")
		)
		(pad "14" smd rect
			(at 0.249936 -1.400048 90)
			(size 0.2286 0.6096)
			(layers "F.Cu" "F.Mask" "F.Paste")
			(net "Net_8633")
		)
		(pad "15" smd rect
			(at -0.249936 -1.400048 90)
			(size 0.2286 0.6096)
			(layers "F.Cu" "F.Mask" "F.Paste")
			(net "Net_8632")
		)
		(pad "16" smd rect
			(at -0.750062 -1.400048 90)
			(size 0.2286 0.6096)
			(layers "F.Cu" "F.Mask" "F.Paste")
			(net "Net_8631")
		)
		(pad "TH" smd rect
			(at 0 0 90)
			(size 1.7018 1.7018)
			(layers "F.Cu" "F.Mask" "F.Paste")
			(net "GND")
		)
		(zone
			(layer "F.Cu")
			(hatch none 0.5)
			(connect_pads
				(clearance 0)
			)
			(min_thickness 0.25)
			(keepout
				(tracks not_allowed)
				(vias allowed)
				(pads allowed)
				(copperpour not_allowed)
				(footprints allowed)
			)
			(placement
				(enabled no)
				(sheetname "")
			)
			(fill
				(thermal_gap 0.5)
				(thermal_bridge_width 0.5)
				(island_removal_mode 0)
			)
			(polygon
				(pts
					(xy 323.486526 -99.164902) (xy 322.467478 -99.164902) (xy 322.467478 -101.253798) (xy 324.556374 -101.253798)
					(xy 324.556374 -99.164902) (xy 323.511926 -99.164902) (xy 323.511926 -99.30765) (xy 324.413626 -99.30765)
					(xy 324.413626 -101.11105) (xy 322.610226 -101.11105) (xy 322.610226 -99.30765) (xy 323.486526 -99.30765)
				)
			)
		)
	)
	(footprint ""
		(layer "F.Cu")
		(at 436.795926 -310.509412 135)
		(property "Reference" "R1441"
			(at 0 0 135)
			(layer "F.SilkS")
			(hide yes)
			(effects
				(font
					(size 1.27 1.27)
				)
			)
		)
		(property "Value" ""
			(at 0 0 135)
			(layer "F.Fab")
			(effects
				(font
					(size 1.27 1.27)
				)
			)
		)
		(duplicate_pad_numbers_are_jumpers no)
		(fp_line
			(start 0.787389 -0.406267)
			(end 0.787389 0.406267)
			(stroke
				(width 0.1524)
				(type default)
			)
			(layer "F.SilkS")
		)
		(fp_line
			(start 0.787389 0.406267)
			(end -0.787389 0.406267)
			(stroke
				(width 0.1524)
				(type default)
			)
			(layer "F.SilkS")
		)
		(fp_line
			(start -0.787389 -0.406267)
			(end 0.787389 -0.406267)
			(stroke
				(width 0.1524)
				(type default)
			)
			(layer "F.SilkS")
		)
		(fp_line
			(start -0.787389 0.406267)
			(end -0.787389 -0.406267)
			(stroke
				(width 0.1524)
				(type default)
			)
			(layer "F.SilkS")
		)
		(fp_line
			(start 0.679446 -0.30479)
			(end 0.679446 0.30479)
			(stroke
				(width 0.1)
				(type default)
			)
			(layer "F.Fab")
		)
		(fp_line
			(start 0.120515 -0.30479)
			(end 0.679446 -0.30479)
			(stroke
				(width 0.1)
				(type default)
			)
			(layer "F.Fab")
		)
		(fp_line
			(start 0.120695 -0.279466)
			(end 0.120515 -0.30479)
			(stroke
				(width 0.1)
				(type default)
			)
			(layer "F.Fab")
		)
		(fp_line
			(start 0.679446 0.30479)
			(end 0.120515 0.30479)
			(stroke
				(width 0.1)
				(type default)
			)
			(layer "F.Fab")
		)
		(fp_line
			(start -0.120695 -0.304969)
			(end -0.120695 -0.279466)
			(stroke
				(width 0.1)
				(type default)
			)
			(layer "F.Fab")
		)
		(fp_line
			(start -0.120695 -0.279466)
			(end 0.120695 -0.279466)
			(stroke
				(width 0.1)
				(type default)
			)
			(layer "F.Fab")
		)
		(fp_line
			(start 0.120335 0.279466)
			(end -0.120695 0.279466)
			(stroke
				(width 0.1)
				(type default)
			)
			(layer "F.Fab")
		)
		(fp_line
			(start 0.120515 0.30479)
			(end 0.120335 0.279466)
			(stroke
				(width 0.1)
				(type default)
			)
			(layer "F.Fab")
		)
		(fp_line
			(start -0.679446 -0.305149)
			(end -0.120695 -0.304969)
			(stroke
				(width 0.1)
				(type default)
			)
			(layer "F.Fab")
		)
		(fp_line
			(start -0.120695 0.279466)
			(end -0.120515 0.30479)
			(stroke
				(width 0.1)
				(type default)
			)
			(layer "F.Fab")
		)
		(fp_line
			(start -0.120515 0.30479)
			(end -0.679446 0.30479)
			(stroke
				(width 0.1)
				(type default)
			)
			(layer "F.Fab")
		)
		(fp_line
			(start -0.679446 0.30479)
			(end -0.679446 -0.305149)
			(stroke
				(width 0.1)
				(type default)
			)
			(layer "F.Fab")
		)
		(pad "1" smd circle
			(at -0.40005 0 135)
			(size 0 0)
			(layers "F.Cu" "F.Mask" "F.Paste")
			(net "PEX3_SPARE2")
		)
		(pad "2" smd circle
			(at 0.40005 0 135)
			(size 0 0)
			(layers "F.Cu" "F.Mask" "F.Paste")
			(net "P1V8_PEX")
		)
	)
	(footprint ""
		(layer "F.Cu")
		(at 157.242764 -70.844918 -90)
		(property "Reference" "PD103"
			(at 3.890518 2.098294 90)
			(unlocked yes)
			(layer "F.SilkS")
			(effects
				(font
					(size 0.7874 0.5842)
					(thickness 0.1524)
				)
				(justify left)
			)
		)
		(property "Value" ""
			(at 0 0 270)
			(layer "F.Fab")
			(effects
				(font
					(size 1.27 1.27)
				)
			)
		)
		(duplicate_pad_numbers_are_jumpers no)
		(fp_line
			(start -3.400044 1.459992)
			(end -3.400044 -1.459992)
			(stroke
				(width 0.1524)
				(type default)
			)
			(layer "F.SilkS")
		)
		(fp_line
			(start 4.107942 1.459992)
			(end -3.400044 1.459992)
			(stroke
				(width 0.1524)
				(type default)
			)
			(layer "F.SilkS")
		)
		(fp_line
			(start -3.400044 -1.459992)
			(end 4.107942 -1.459992)
			(stroke
				(width 0.1524)
				(type default)
			)
			(layer "F.SilkS")
		)
		(fp_line
			(start 4.107942 -1.459992)
			(end 4.107942 1.459992)
			(stroke
				(width 0.1524)
				(type default)
			)
			(layer "F.SilkS")
		)
		(fp_poly
			(pts
				(xy 4.107942 -1.459992) (xy 4.107942 1.459992) (xy 3.308096 1.459992) (xy 3.308096 -1.459992)
			)
			(stroke
				(width 0)
				(type default)
			)
			(fill yes)
			(layer "F.SilkS")
		)
		(fp_line
			(start -2.29997 1.459992)
			(end -2.29997 -1.459992)
			(stroke
				(width 0.1)
				(type default)
			)
			(layer "F.Fab")
		)
		(fp_line
			(start 2.29997 1.459992)
			(end -2.29997 1.459992)
			(stroke
				(width 0.1)
				(type default)
			)
			(layer "F.Fab")
		)
		(fp_line
			(start -2.29997 -1.459992)
			(end 2.29997 -1.459992)
			(stroke
				(width 0.1)
				(type default)
			)
			(layer "F.Fab")
		)
		(fp_line
			(start 2.29997 -1.459992)
			(end 2.29997 1.459992)
			(stroke
				(width 0.1)
				(type default)
			)
			(layer "F.Fab")
		)
		(fp_text user "-"
			(at 5.4102 0.29845 90)
			(unlocked yes)
			(layer "F.SilkS")
			(effects
				(font
					(size 1.905 1.4224)
					(thickness 0.1524)
				)
				(justify left)
			)
		)
		(fp_text user "+"
			(at -4.838954 -1.230884 270)
			(unlocked yes)
			(layer "F.SilkS")
			(effects
				(font
					(size 1.905 1.4224)
					(thickness 0.1524)
				)
				(justify left)
			)
		)
		(fp_text user "-"
			(at 5.4102 0.29845 90)
			(unlocked yes)
			(layer "F.Fab")
			(effects
				(font
					(size 1.905 1.4224)
					(thickness 0.1524)
				)
				(justify left)
			)
		)
		(fp_text user "+"
			(at -4.7752 -0.12065 270)
			(unlocked yes)
			(layer "F.Fab")
			(effects
				(font
					(size 1.905 1.4224)
					(thickness 0.1524)
				)
				(justify left)
			)
		)
		(pad "A" smd rect
			(at -1.999996 0)
			(size 1.7018 2.5146)
			(layers "F.Cu" "F.Mask" "F.Paste")
			(net "GND")
		)
		(pad "C" smd rect
			(at 1.999996 0)
			(size 1.7018 2.5146)
			(layers "F.Cu" "F.Mask" "F.Paste")
			(net "P12V_SSD5_R")
		)
	)
	(footprint ""
		(layer "F.Cu")
		(at 314.861448 -152.511252 180)
		(property "Reference" "C427"
			(at 0 0 180)
			(layer "F.SilkS")
			(hide yes)
			(effects
				(font
					(size 1.27 1.27)
				)
			)
		)
		(property "Value" ""
			(at 0 0 180)
			(layer "F.Fab")
			(effects
				(font
					(size 1.27 1.27)
				)
			)
		)
		(duplicate_pad_numbers_are_jumpers no)
		(fp_line
			(start 0.299974 0.150114)
			(end -0.299974 0.150114)
			(stroke
				(width 0.1)
				(type default)
			)
			(layer "F.Fab")
		)
		(fp_line
			(start 0.299974 -0.150114)
			(end 0.299974 0.150114)
			(stroke
				(width 0.1)
				(type default)
			)
			(layer "F.Fab")
		)
		(fp_line
			(start -0.299974 0.150114)
			(end -0.299974 -0.150114)
			(stroke
				(width 0.1)
				(type default)
			)
			(layer "F.Fab")
		)
		(fp_line
			(start -0.299974 -0.150114)
			(end 0.299974 -0.150114)
			(stroke
				(width 0.1)
				(type default)
			)
			(layer "F.Fab")
		)
		(pad "1" smd rect
			(at -0.2667 0 180)
			(size 0.3048 0.381)
			(layers "F.Cu" "F.Mask" "F.Paste")
			(net "P5E_PEX2_STN0_TX_DP<13>")
		)
		(pad "2" smd rect
			(at 0.2667 0 180)
			(size 0.3048 0.381)
			(layers "F.Cu" "F.Mask" "F.Paste")
			(net "P5E_PEX2_STN0_TX_C_DP<13>")
		)
	)
	(footprint ""
		(layer "F.Cu")
		(at 369.495578 -82.641694 180)
		(property "Reference" "R1603"
			(at 0 0 180)
			(layer "F.SilkS")
			(hide yes)
			(effects
				(font
					(size 1.27 1.27)
				)
			)
		)
		(property "Value" ""
			(at 0 0 180)
			(layer "F.Fab")
			(effects
				(font
					(size 1.27 1.27)
				)
			)
		)
		(duplicate_pad_numbers_are_jumpers no)
		(fp_line
			(start 0.7874 0.4064)
			(end -0.7874 0.4064)
			(stroke
				(width 0.1524)
				(type default)
			)
			(layer "F.SilkS")
		)
		(fp_line
			(start 0.7874 -0.4064)
			(end 0.7874 0.4064)
			(stroke
				(width 0.1524)
				(type default)
			)
			(layer "F.SilkS")
		)
		(fp_line
			(start -0.7874 0.4064)
			(end -0.7874 -0.4064)
			(stroke
				(width 0.1524)
				(type default)
			)
			(layer "F.SilkS")
		)
		(fp_line
			(start -0.7874 -0.4064)
			(end 0.7874 -0.4064)
			(stroke
				(width 0.1524)
				(type default)
			)
			(layer "F.SilkS")
		)
		(fp_line
			(start 0.67945 0.3048)
			(end 0.120396 0.3048)
			(stroke
				(width 0.1)
				(type default)
			)
			(layer "F.Fab")
		)
		(fp_line
			(start 0.67945 -0.3048)
			(end 0.67945 0.3048)
			(stroke
				(width 0.1)
				(type default)
			)
			(layer "F.Fab")
		)
		(fp_line
			(start 0.12065 -0.2794)
			(end 0.12065 -0.3048)
			(stroke
				(width 0.1)
				(type default)
			)
			(layer "F.Fab")
		)
		(fp_line
			(start 0.12065 -0.3048)
			(end 0.67945 -0.3048)
			(stroke
				(width 0.1)
				(type default)
			)
			(layer "F.Fab")
		)
		(fp_line
			(start 0.120396 0.3048)
			(end 0.120396 0.2794)
			(stroke
				(width 0.1)
				(type default)
			)
			(layer "F.Fab")
		)
		(fp_line
			(start 0.120396 0.2794)
			(end -0.12065 0.2794)
			(stroke
				(width 0.1)
				(type default)
			)
			(layer "F.Fab")
		)
		(fp_line
			(start -0.12065 0.3048)
			(end -0.67945 0.3048)
			(stroke
				(width 0.1)
				(type default)
			)
			(layer "F.Fab")
		)
		(fp_line
			(start -0.12065 0.2794)
			(end -0.12065 0.3048)
			(stroke
				(width 0.1)
				(type default)
			)
			(layer "F.Fab")
		)
		(fp_line
			(start -0.12065 -0.2794)
			(end 0.12065 -0.2794)
			(stroke
				(width 0.1)
				(type default)
			)
			(layer "F.Fab")
		)
		(fp_line
			(start -0.12065 -0.305054)
			(end -0.12065 -0.2794)
			(stroke
				(width 0.1)
				(type default)
			)
			(layer "F.Fab")
		)
		(fp_line
			(start -0.67945 0.3048)
			(end -0.67945 -0.305054)
			(stroke
				(width 0.1)
				(type default)
			)
			(layer "F.Fab")
		)
		(fp_line
			(start -0.67945 -0.305054)
			(end -0.12065 -0.305054)
			(stroke
				(width 0.1)
				(type default)
			)
			(layer "F.Fab")
		)
		(pad "1" smd circle
			(at -0.40005 0 180)
			(size 0 0)
			(layers "F.Cu" "F.Mask" "F.Paste")
			(net "P3V3_AUX")
		)
		(pad "2" smd circle
			(at 0.40005 0 180)
			(size 0 0)
			(layers "F.Cu" "F.Mask" "F.Paste")
			(net "SMB_BIC_I2C9_MUX1_SSD12_R_SCL")
		)
	)
)
